# T6G (Grand Teton) — schematic netlist excerpt (pin names and nets, part order shuffled) for the footprints in the layout excerpt that follows; sources: Cadence DE-HDL packaged netlist, KiCad conversion of 04192023_DAF0TMB3IC0_F0TG_MB_C_brd_V02_OCP.brd

R167  Q_RES  0 5% CHIP  pkg 0402LF  page 80 : A = SGPIO_SCM_DI_R<0> ; B = SGPIO_SCM_DI_<0>
R6322  Q_RES  0 5% CHIP  pkg 0402LF  page 178 : A = RST_USB_HUB_N ; B = USB_HUB2_MRP_RESET_N

(kicad_pcb
	(version 20260206)
	(generator "pcbnew")
	(generator_version "10.0")
	(general
		(thickness 1.6)
		(legacy_teardrops no)
	)
	(paper "A4")
	(title_block
		(title "04192023_DAF0TMB3IC0_F0TG_MB_C_brd_V02_OCP.brd")
		(comment 1 "Grand Teton / footprints 1790-1791 of 8354")
	)
	(layers
		(0 "F.Cu" signal "TOP")
		(4 "In1.Cu" signal "GND")
		(6 "In2.Cu" signal "IN1")
		(8 "In3.Cu" signal "GND1")
		(10 "In4.Cu" signal "IN2")
		(12 "In5.Cu" signal "GND2")
		(14 "In6.Cu" signal "IN3")
		(16 "In7.Cu" signal "GND3")
		(18 "In8.Cu" signal "VCC")
		(20 "In9.Cu" signal "VCC1")
		(22 "In10.Cu" signal "GND4")
		(24 "In11.Cu" signal "IN4")
		(26 "In12.Cu" signal "GND5")
		(28 "In13.Cu" signal "IN5")
		(30 "In14.Cu" signal "GND6")
		(32 "In15.Cu" signal "IN6")
		(34 "In16.Cu" signal "GND7")
		(2 "B.Cu" signal "BOTTOM")
		(9 "F.Adhes" user "F.Adhesive")
		(11 "B.Adhes" user "B.Adhesive")
		(13 "F.Paste" user "Package Geometry/Pastemask Top")
		(15 "B.Paste" user "Package Geometry/Pastemask Bottom")
		(5 "F.SilkS" user "Ref Des/Silkscreen Top")
		(7 "B.SilkS" user "Ref Des/Silkscreen Bottom")
		(1 "F.Mask" user "Board Geometry/Soldermask Top")
		(3 "B.Mask" user "Board Geometry/Soldermask Bottom")
		(17 "Dwgs.User" user "User.Drawings")
		(19 "Cmts.User" user "User.Comments")
		(21 "Eco1.User" user "User.Eco1")
		(23 "Eco2.User" user "User.Eco2")
		(25 "Edge.Cuts" user "Board Geometry/Outline")
		(27 "Margin" user)
		(31 "F.CrtYd" user "Package Geometry/Place Bound Top")
		(29 "B.CrtYd" user "Package Geometry/Place Bound Bottom")
		(35 "F.Fab" user "Ref Des/Assembly Top")
		(33 "B.Fab" user "Ref Des/Assembly Bottom")
	)
	(footprint ""
		(layer "F.Cu")
		(at 171.196 -109.184948 180)
		(property "Reference" "R167"
			(at 0 0 180)
			(layer "F.SilkS")
			(hide yes)
			(effects
				(font
					(size 1.27 1.27)
				)
			)
		)
		(property "Value" ""
			(at 0 0 180)
			(layer "F.Fab")
			(effects
				(font
					(size 1.27 1.27)
				)
			)
		)
		(duplicate_pad_numbers_are_jumpers no)
		(fp_line
			(start 0.7874 0.4064)
			(end -0.7874 0.4064)
			(stroke
				(width 0.1524)
				(type default)
			)
			(layer "F.SilkS")
		)
		(fp_line
			(start 0.7874 -0.4064)
			(end 0.7874 0.4064)
			(stroke
				(width 0.1524)
				(type default)
			)
			(layer "F.SilkS")
		)
		(fp_line
			(start -0.7874 0.4064)
			(end -0.7874 -0.4064)
			(stroke
				(width 0.1524)
				(type default)
			)
			(layer "F.SilkS")
		)
		(fp_line
			(start -0.7874 -0.4064)
			(end 0.7874 -0.4064)
			(stroke
				(width 0.1524)
				(type default)
			)
			(layer "F.SilkS")
		)
		(fp_line
			(start 0.67945 0.3048)
			(end 0.120396 0.3048)
			(stroke
				(width 0.1)
				(type default)
			)
			(layer "F.Fab")
		)
		(fp_line
			(start 0.67945 -0.3048)
			(end 0.67945 0.3048)
			(stroke
				(width 0.1)
				(type default)
			)
			(layer "F.Fab")
		)
		(fp_line
			(start 0.12065 -0.2794)
			(end 0.12065 -0.3048)
			(stroke
				(width 0.1)
				(type default)
			)
			(layer "F.Fab")
		)
		(fp_line
			(start 0.12065 -0.3048)
			(end 0.67945 -0.3048)
			(stroke
				(width 0.1)
				(type default)
			)
			(layer "F.Fab")
		)
		(fp_line
			(start 0.120396 0.3048)
			(end 0.120396 0.2794)
			(stroke
				(width 0.1)
				(type default)
			)
			(layer "F.Fab")
		)
		(fp_line
			(start 0.120396 0.2794)
			(end -0.12065 0.2794)
			(stroke
				(width 0.1)
				(type default)
			)
			(layer "F.Fab")
		)
		(fp_line
			(start -0.12065 0.3048)
			(end -0.67945 0.3048)
			(stroke
				(width 0.1)
				(type default)
			)
			(layer "F.Fab")
		)
		(fp_line
			(start -0.12065 0.2794)
			(end -0.12065 0.3048)
			(stroke
				(width 0.1)
				(type default)
			)
			(layer "F.Fab")
		)
		(fp_line
			(start -0.12065 -0.2794)
			(end 0.12065 -0.2794)
			(stroke
				(width 0.1)
				(type default)
			)
			(layer "F.Fab")
		)
		(fp_line
			(start -0.12065 -0.305054)
			(end -0.12065 -0.2794)
			(stroke
				(width 0.1)
				(type default)
			)
			(layer "F.Fab")
		)
		(fp_line
			(start -0.67945 0.3048)
			(end -0.67945 -0.305054)
			(stroke
				(width 0.1)
				(type default)
			)
			(layer "F.Fab")
		)
		(fp_line
			(start -0.67945 -0.305054)
			(end -0.12065 -0.305054)
			(stroke
				(width 0.1)
				(type default)
			)
			(layer "F.Fab")
		)
		(pad "1" smd circle
			(at -0.40005 0 180)
			(size 0 0)
			(layers "F.Cu" "F.Mask" "F.Paste")
			(net "SGPIO_SCM_DI_R<0>")
		)
		(pad "2" smd circle
			(at 0.40005 0 180)
			(size 0 0)
			(layers "F.Cu" "F.Mask" "F.Paste")
			(net "SGPIO_SCM_DI_<0>")
		)
	)
	(footprint ""
		(layer "F.Cu")
		(at 102.437946 -54.882034 -90)
		(property "Reference" "R6322"
			(at 0 0 270)
			(layer "F.SilkS")
			(hide yes)
			(effects
				(font
					(size 1.27 1.27)
				)
			)
		)
		(property "Value" ""
			(at 0 0 270)
			(layer "F.Fab")
			(effects
				(font
					(size 1.27 1.27)
				)
			)
		)
		(duplicate_pad_numbers_are_jumpers no)
		(fp_line
			(start -0.7874 0.4064)
			(end -0.7874 -0.4064)
			(stroke
				(width 0.1524)
				(type default)
			)
			(layer "F.SilkS")
		)
		(fp_line
			(start 0.7874 0.4064)
			(end -0.7874 0.4064)
			(stroke
				(width 0.1524)
				(type default)
			)
			(layer "F.SilkS")
		)
		(fp_line
			(start -0.7874 -0.4064)
			(end 0.7874 -0.4064)
			(stroke
				(width 0.1524)
				(type default)
			)
			(layer "F.SilkS")
		)
		(fp_line
			(start 0.7874 -0.4064)
			(end 0.7874 0.4064)
			(stroke
				(width 0.1524)
				(type default)
			)
			(layer "F.SilkS")
		)
		(fp_line
			(start -0.67945 0.3048)
			(end -0.67945 -0.305054)
			(stroke
				(width 0.1)
				(type default)
			)
			(layer "F.Fab")
		)
		(fp_line
			(start -0.12065 0.3048)
			(end -0.67945 0.3048)
			(stroke
				(width 0.1)
				(type default)
			)
			(layer "F.Fab")
		)
		(fp_line
			(start 0.120396 0.3048)
			(end 0.120396 0.2794)
			(stroke
				(width 0.1)
				(type default)
			)
			(layer "F.Fab")
		)
		(fp_line
			(start 0.67945 0.3048)
			(end 0.120396 0.3048)
			(stroke
				(width 0.1)
				(type default)
			)
			(layer "F.Fab")
		)
		(fp_line
			(start -0.12065 0.2794)
			(end -0.12065 0.3048)
			(stroke
				(width 0.1)
				(type default)
			)
			(layer "F.Fab")
		)
		(fp_line
			(start 0.120396 0.2794)
			(end -0.12065 0.2794)
			(stroke
				(width 0.1)
				(type default)
			)
			(layer "F.Fab")
		)
		(fp_line
			(start -0.12065 -0.2794)
			(end 0.12065 -0.2794)
			(stroke
				(width 0.1)
				(type default)
			)
			(layer "F.Fab")
		)
		(fp_line
			(start 0.12065 -0.2794)
			(end 0.12065 -0.3048)
			(stroke
				(width 0.1)
				(type default)
			)
			(layer "F.Fab")
		)
		(fp_line
			(start 0.12065 -0.3048)
			(end 0.67945 -0.3048)
			(stroke
				(width 0.1)
				(type default)
			)
			(layer "F.Fab")
		)
		(fp_line
			(start 0.67945 -0.3048)
			(end 0.67945 0.3048)
			(stroke
				(width 0.1)
				(type default)
			)
			(layer "F.Fab")
		)
		(fp_line
			(start -0.67945 -0.305054)
			(end -0.12065 -0.305054)
			(stroke
				(width 0.1)
				(type default)
			)
			(layer "F.Fab")
		)
		(fp_line
			(start -0.12065 -0.305054)
			(end -0.12065 -0.2794)
			(stroke
				(width 0.1)
				(type default)
			)
			(layer "F.Fab")
		)
		(pad "1" smd circle
			(at -0.40005 0 270)
			(size 0 0)
			(layers "F.Cu" "F.Mask" "F.Paste")
			(net "RST_USB_HUB_N")
		)
		(pad "2" smd circle
			(at 0.40005 0 270)
			(size 0 0)
			(layers "F.Cu" "F.Mask" "F.Paste")
			(net "USB_HUB2_MRP_RESET_N")
		)
	)
)
